# T6G (Grand Teton) — schematic netlist excerpt (pin names and nets, part order shuffled) for the footprints in the layout excerpt that follows; sources: Cadence DE-HDL packaged netlist, KiCad conversion of 04192023_DAF0TMB3IC0_F0TG_MB_C_brd_V02_OCP.brd

C2125  Q_CAP  22UF 4V 20% X6S  pkg C0402  page 74 : A = PVDD11_S3_P1 ; B = GND
C787  Q_CAP  1UF 4V 20% X6S  pkg 0201  page 301 : A = P0V9_CPU0_RT2_2A_2D ; B = GND
L22  Q_INDUCTOR  BLM21SN300SN1D/5A IND  pkg SMLF  page 312 : \1\ = P1V8_CPU0_RT_1D ; \2\ = P1V8_CPU0_RT3_1A

(kicad_pcb
	(version 20260206)
	(generator "pcbnew")
	(generator_version "10.0")
	(general
		(thickness 1.6)
		(legacy_teardrops no)
	)
	(paper "A4")
	(title_block
		(title "04192023_DAF0TMB3IC0_F0TG_MB_C_brd_V02_OCP.brd")
		(comment 1 "Grand Teton / footprints 5113-5115 of 8354")
	)
	(layers
		(0 "F.Cu" signal "TOP")
		(4 "In1.Cu" signal "GND")
		(6 "In2.Cu" signal "IN1")
		(8 "In3.Cu" signal "GND1")
		(10 "In4.Cu" signal "IN2")
		(12 "In5.Cu" signal "GND2")
		(14 "In6.Cu" signal "IN3")
		(16 "In7.Cu" signal "GND3")
		(18 "In8.Cu" signal "VCC")
		(20 "In9.Cu" signal "VCC1")
		(22 "In10.Cu" signal "GND4")
		(24 "In11.Cu" signal "IN4")
		(26 "In12.Cu" signal "GND5")
		(28 "In13.Cu" signal "IN5")
		(30 "In14.Cu" signal "GND6")
		(32 "In15.Cu" signal "IN6")
		(34 "In16.Cu" signal "GND7")
		(2 "B.Cu" signal "BOTTOM")
		(9 "F.Adhes" user "F.Adhesive")
		(11 "B.Adhes" user "B.Adhesive")
		(13 "F.Paste" user "Package Geometry/Pastemask Top")
		(15 "B.Paste" user "Package Geometry/Pastemask Bottom")
		(5 "F.SilkS" user "Ref Des/Silkscreen Top")
		(7 "B.SilkS" user "Ref Des/Silkscreen Bottom")
		(1 "F.Mask" user "Board Geometry/Soldermask Top")
		(3 "B.Mask" user "Board Geometry/Soldermask Bottom")
		(17 "Dwgs.User" user "User.Drawings")
		(19 "Cmts.User" user "User.Comments")
		(21 "Eco1.User" user "User.Eco1")
		(23 "Eco2.User" user "User.Eco2")
		(25 "Edge.Cuts" user "Board Geometry/Outline")
		(27 "Margin" user)
		(31 "F.CrtYd" user "Package Geometry/Place Bound Top")
		(29 "B.CrtYd" user "Package Geometry/Place Bound Bottom")
		(35 "F.Fab" user "Ref Des/Assembly Top")
		(33 "B.Fab" user "Ref Des/Assembly Bottom")
	)
	(footprint ""
		(layer "B.Cu")
		(at 109.577124 -261.748016 90)
		(property "Reference" "C2125"
			(at 0 0 90)
			(layer "B.SilkS")
			(hide yes)
			(effects
				(font
					(size 1.27 1.27)
				)
				(justify mirror)
			)
		)
		(property "Value" ""
			(at 0 0 90)
			(layer "B.Fab")
			(effects
				(font
					(size 1.27 1.27)
				)
				(justify mirror)
			)
		)
		(duplicate_pad_numbers_are_jumpers no)
		(fp_line
			(start 0.7874 -0.4064)
			(end -0.7874 -0.4064)
			(stroke
				(width 0.1524)
				(type default)
			)
			(layer "B.SilkS")
		)
		(fp_line
			(start -0.7874 -0.4064)
			(end -0.7874 0.4064)
			(stroke
				(width 0.1524)
				(type default)
			)
			(layer "B.SilkS")
		)
		(fp_line
			(start 0.7874 0.4064)
			(end 0.7874 -0.4064)
			(stroke
				(width 0.1524)
				(type default)
			)
			(layer "B.SilkS")
		)
		(fp_line
			(start -0.7874 0.4064)
			(end 0.7874 0.4064)
			(stroke
				(width 0.1524)
				(type default)
			)
			(layer "B.SilkS")
		)
		(fp_line
			(start 0.67945 -0.305054)
			(end 0.12065 -0.305054)
			(stroke
				(width 0.1)
				(type default)
			)
			(layer "B.Fab")
		)
		(fp_line
			(start 0.12065 -0.305054)
			(end 0.12065 -0.2794)
			(stroke
				(width 0.1)
				(type default)
			)
			(layer "B.Fab")
		)
		(fp_line
			(start -0.12065 -0.3048)
			(end -0.67945 -0.3048)
			(stroke
				(width 0.1)
				(type default)
			)
			(layer "B.Fab")
		)
		(fp_line
			(start -0.67945 -0.3048)
			(end -0.67945 0.3048)
			(stroke
				(width 0.1)
				(type default)
			)
			(layer "B.Fab")
		)
		(fp_line
			(start 0.12065 -0.2794)
			(end -0.12065 -0.2794)
			(stroke
				(width 0.1)
				(type default)
			)
			(layer "B.Fab")
		)
		(fp_line
			(start -0.12065 -0.2794)
			(end -0.12065 -0.3048)
			(stroke
				(width 0.1)
				(type default)
			)
			(layer "B.Fab")
		)
		(fp_line
			(start 0.12065 0.2794)
			(end 0.12065 0.3048)
			(stroke
				(width 0.1)
				(type default)
			)
			(layer "B.Fab")
		)
		(fp_line
			(start -0.120396 0.2794)
			(end 0.12065 0.2794)
			(stroke
				(width 0.1)
				(type default)
			)
			(layer "B.Fab")
		)
		(fp_line
			(start 0.67945 0.3048)
			(end 0.67945 -0.305054)
			(stroke
				(width 0.1)
				(type default)
			)
			(layer "B.Fab")
		)
		(fp_line
			(start 0.12065 0.3048)
			(end 0.67945 0.3048)
			(stroke
				(width 0.1)
				(type default)
			)
			(layer "B.Fab")
		)
		(fp_line
			(start -0.120396 0.3048)
			(end -0.120396 0.2794)
			(stroke
				(width 0.1)
				(type default)
			)
			(layer "B.Fab")
		)
		(fp_line
			(start -0.67945 0.3048)
			(end -0.120396 0.3048)
			(stroke
				(width 0.1)
				(type default)
			)
			(layer "B.Fab")
		)
		(pad "1" smd circle
			(at 0.40005 0 270)
			(size 0 0)
			(layers "B.Cu" "B.Mask" "B.Paste")
			(net "PVDD11_S3_P1")
		)
		(pad "2" smd circle
			(at -0.40005 0 270)
			(size 0 0)
			(layers "B.Cu" "B.Mask" "B.Paste")
			(net "GND")
		)
	)
	(footprint ""
		(layer "B.Cu")
		(at 407.806144 -395.148562 90)
		(property "Reference" "C787"
			(at 0 0 90)
			(layer "B.SilkS")
			(hide yes)
			(effects
				(font
					(size 1.27 1.27)
				)
				(justify mirror)
			)
		)
		(property "Value" ""
			(at 0 0 90)
			(layer "B.Fab")
			(effects
				(font
					(size 1.27 1.27)
				)
				(justify mirror)
			)
		)
		(duplicate_pad_numbers_are_jumpers no)
		(fp_line
			(start 0.299974 -0.150114)
			(end -0.299974 -0.150114)
			(stroke
				(width 0.1)
				(type default)
			)
			(layer "B.Fab")
		)
		(fp_line
			(start -0.299974 -0.150114)
			(end -0.299974 0.150114)
			(stroke
				(width 0.1)
				(type default)
			)
			(layer "B.Fab")
		)
		(fp_line
			(start 0.299974 0.150114)
			(end 0.299974 -0.150114)
			(stroke
				(width 0.1)
				(type default)
			)
			(layer "B.Fab")
		)
		(fp_line
			(start -0.299974 0.150114)
			(end 0.299974 0.150114)
			(stroke
				(width 0.1)
				(type default)
			)
			(layer "B.Fab")
		)
		(pad "1" smd rect
			(at 0.2667 0 270)
			(size 0.3048 0.381)
			(layers "B.Cu" "B.Mask" "B.Paste")
			(net "P0V9_CPU0_RT2_2A_2D")
		)
		(pad "2" smd rect
			(at -0.2667 0 270)
			(size 0.3048 0.381)
			(layers "B.Cu" "B.Mask" "B.Paste")
			(net "GND")
		)
	)
	(footprint ""
		(layer "B.Cu")
		(at 393.352274 -392.957558)
		(property "Reference" "L22"
			(at 0 0 0)
			(layer "B.SilkS")
			(hide yes)
			(effects
				(font
					(size 1.27 1.27)
				)
				(justify mirror)
			)
		)
		(property "Value" ""
			(at 0 0 0)
			(layer "B.Fab")
			(effects
				(font
					(size 1.27 1.27)
				)
				(justify mirror)
			)
		)
		(duplicate_pad_numbers_are_jumpers no)
		(fp_line
			(start -1.63576 -0.8128)
			(end -1.63576 0.8128)
			(stroke
				(width 0.1524)
				(type default)
			)
			(layer "B.SilkS")
		)
		(fp_line
			(start -1.63576 0.8128)
			(end 1.63576 0.8128)
			(stroke
				(width 0.1524)
				(type default)
			)
			(layer "B.SilkS")
		)
		(fp_line
			(start 1.63576 -0.8128)
			(end -1.63576 -0.8128)
			(stroke
				(width 0.1524)
				(type default)
			)
			(layer "B.SilkS")
		)
		(fp_line
			(start 1.63576 -0.8128)
			(end 1.63576 0.8128)
			(stroke
				(width 0.1524)
				(type default)
			)
			(layer "B.SilkS")
		)
		(fp_line
			(start -1.560576 -0.738632)
			(end 1.56083 -0.738632)
			(stroke
				(width 0.1)
				(type default)
			)
			(layer "B.Fab")
		)
		(fp_line
			(start -1.560576 0.7366)
			(end -1.560576 -0.738632)
			(stroke
				(width 0.1)
				(type default)
			)
			(layer "B.Fab")
		)
		(fp_line
			(start -1.524 0.7366)
			(end -1.560576 0.7366)
			(stroke
				(width 0.1)
				(type default)
			)
			(layer "B.Fab")
		)
		(fp_line
			(start 1.524 0.7366)
			(end -1.524 0.7366)
			(stroke
				(width 0.1)
				(type default)
			)
			(layer "B.Fab")
		)
		(fp_line
			(start 1.56083 -0.738632)
			(end 1.56083 0.7366)
			(stroke
				(width 0.1)
				(type default)
			)
			(layer "B.Fab")
		)
		(fp_line
			(start 1.56083 0.7366)
			(end 1.524 0.7366)
			(stroke
				(width 0.1)
				(type default)
			)
			(layer "B.Fab")
		)
		(pad "1" smd rect
			(at 0.94996 0)
			(size 1.1176 1.3716)
			(layers "B.Cu" "B.Mask" "B.Paste")
			(net "P1V8_CPU0_RT_1D")
		)
		(pad "2" smd rect
			(at -0.94996 0)
			(size 1.1176 1.3716)
			(layers "B.Cu" "B.Mask" "B.Paste")
			(net "P1V8_CPU0_RT3_1A")
		)
	)
)
